(kicad_pcb
	(version 20260206)
	(generator "pcbnew")
	(generator_version "10.0")
	(general
		(thickness 1.6)
		(legacy_teardrops no)
	)
	(paper "A4")
	(title_block
		(title "Wiwynn_Tioga_Pass_MB.brd")
		(comment 1 "Tioga Pass / footprints 1516-1522 of 4770")
	)
	(layers
		(0 "F.Cu" signal "TOP")
		(4 "In1.Cu" signal "L2GND")
		(6 "In2.Cu" signal "L3")
		(8 "In3.Cu" signal "L4GND")
		(10 "In4.Cu" signal "L5")
		(12 "In5.Cu" signal "L6GND")
		(14 "In6.Cu" signal "L7VCC")
		(16 "In7.Cu" signal "L8VCC")
		(18 "In8.Cu" signal "L9GND")
		(20 "In9.Cu" signal "L10")
		(22 "In10.Cu" signal "L11GND")
		(24 "In11.Cu" signal "L12")
		(26 "In12.Cu" signal "L13GND")
		(2 "B.Cu" signal "BOTTOM")
		(9 "F.Adhes" user "F.Adhesive")
		(11 "B.Adhes" user "B.Adhesive")
		(13 "F.Paste" user "Package Geometry/Pastemask Top")
		(15 "B.Paste" user "Package Geometry/Pastemask Bottom")
		(5 "F.SilkS" user "Ref Des/Silkscreen Top")
		(7 "B.SilkS" user "Ref Des/Silkscreen Bottom")
		(1 "F.Mask" user "Board Geometry/Soldermask Top")
		(3 "B.Mask" user "Board Geometry/Soldermask Bottom")
		(17 "Dwgs.User" user "User.Drawings")
		(19 "Cmts.User" user "User.Comments")
		(21 "Eco1.User" user "User.Eco1")
		(23 "Eco2.User" user "User.Eco2")
		(25 "Edge.Cuts" user "Board Geometry/Outline")
		(27 "Margin" user)
		(31 "F.CrtYd" user "Package Geometry/Place Bound Top")
		(29 "B.CrtYd" user "Package Geometry/Place Bound Bottom")
		(35 "F.Fab" user "Ref Des/Assembly Top")
		(33 "B.Fab" user "Ref Des/Assembly Bottom")
	)
	(footprint ""
		(layer "F.Cu")
		(at 422.148 -84.3915)
		(property "Reference" "R8D26"
			(at 0 0 0)
			(layer "F.SilkS")
			(hide yes)
			(effects
				(font
					(size 1.27 1.27)
				)
			)
		)
		(property "Value" ""
			(at 0 0 0)
			(layer "F.Fab")
			(effects
				(font
					(size 1.27 1.27)
				)
			)
		)
		(duplicate_pad_numbers_are_jumpers no)
		(fp_poly
			(pts
				(xy -0.2794 -0.1016) (xy 0.2794 -0.1016) (xy 0.2794 0.9906) (xy -0.2794 0.9906)
			)
			(stroke
				(width 0)
				(type default)
			)
			(fill no)
			(layer "F.CrtYd")
		)
		(fp_line
			(start -0.2794 -0.1016)
			(end -0.2794 0.9906)
			(stroke
				(width 0.1)
				(type default)
			)
			(layer "F.Fab")
		)
		(fp_line
			(start -0.2794 0.9906)
			(end 0.2794 0.9906)
			(stroke
				(width 0.1)
				(type default)
			)
			(layer "F.Fab")
		)
		(fp_line
			(start 0.2794 -0.1016)
			(end -0.2794 -0.1016)
			(stroke
				(width 0.1)
				(type default)
			)
			(layer "F.Fab")
		)
		(fp_line
			(start 0.2794 0.9906)
			(end 0.2794 -0.1016)
			(stroke
				(width 0.1)
				(type default)
			)
			(layer "F.Fab")
		)
		(pad "1" smd rect
			(at 0 0)
			(size 0.508 0.508)
			(layers "F.Cu" "F.Mask" "F.Paste")
			(net "P3V3_STBY")
		)
		(pad "2" smd rect
			(at 0 0.889)
			(size 0.508 0.508)
			(layers "F.Cu" "F.Mask" "F.Paste")
			(net "IRQ_SML1_PMBUS_ALERT_BUF_N")
		)
		(zone
			(layer "F.Cu")
			(hatch none 0.5)
			(connect_pads
				(clearance 0)
			)
			(min_thickness 0.25)
			(keepout
				(tracks allowed)
				(vias not_allowed)
				(pads allowed)
				(copperpour not_allowed)
				(footprints allowed)
			)
			(placement
				(enabled no)
				(sheetname "")
			)
			(fill
				(thermal_gap 0.5)
				(thermal_bridge_width 0.5)
				(island_removal_mode 0)
			)
			(polygon
				(pts
					(xy 421.894 -84.1375) (xy 422.402 -84.1375) (xy 422.402 -83.7565) (xy 421.894 -83.7565)
				)
			)
		)
		(zone
			(layer "F.Cu")
			(hatch none 0.5)
			(connect_pads
				(clearance 0)
			)
			(min_thickness 0.25)
			(keepout
				(tracks not_allowed)
				(vias allowed)
				(pads allowed)
				(copperpour not_allowed)
				(footprints allowed)
			)
			(placement
				(enabled no)
				(sheetname "")
			)
			(fill
				(thermal_gap 0.5)
				(thermal_bridge_width 0.5)
				(island_removal_mode 0)
			)
			(polygon
				(pts
					(xy 421.894 -83.7565) (xy 422.402 -83.7565) (xy 422.402 -84.1375) (xy 421.894 -84.1375)
				)
			)
		)
	)
	(footprint ""
		(layer "F.Cu")
		(at 29.337 13.2715 -90)
		(property "Reference" "T1P35"
			(at 0 0 270)
			(layer "F.SilkS")
			(hide yes)
			(effects
				(font
					(size 1.27 1.27)
				)
			)
		)
		(property "Value" "*"
			(at 0 -3.44805 270)
			(unlocked yes)
			(layer "F.Fab")
			(hide yes)
			(effects
				(font
					(size 0.889 0.889)
					(thickness 0.1524)
				)
			)
		)
		(property "Device Type" "TPAD-SE-2P-GP_DISCRET-GA1-TPADA"
			(at 0 -4.97205 270)
			(unlocked yes)
			(layer "F.Fab")
			(hide yes)
			(effects
				(font
					(size 0.889 0.889)
					(thickness 0.1524)
				)
			)
		)
		(duplicate_pad_numbers_are_jumpers no)
		(fp_line
			(start -1.016 2.286)
			(end -1.016 -2.286)
			(stroke
				(width 0.1524)
				(type default)
			)
			(layer "F.SilkS")
		)
		(fp_line
			(start 1.016 2.286)
			(end -1.016 2.286)
			(stroke
				(width 0.1524)
				(type default)
			)
			(layer "F.SilkS")
		)
		(fp_line
			(start -1.016 -2.286)
			(end 1.016 -2.286)
			(stroke
				(width 0.1524)
				(type default)
			)
			(layer "F.SilkS")
		)
		(fp_line
			(start 1.016 -2.286)
			(end 1.016 2.286)
			(stroke
				(width 0.1524)
				(type default)
			)
			(layer "F.SilkS")
		)
		(fp_rect
			(start -1.27 2.54)
			(end 1.27 -2.54)
			(stroke
				(width 0)
				(type default)
			)
			(fill no)
			(layer "F.CrtYd")
		)
		(fp_rect
			(start -1.27 2.54)
			(end 1.27 -2.54)
			(stroke
				(width 0)
				(type default)
			)
			(fill no)
			(layer "F.Fab")
		)
		(pad "1" thru_hole circle
			(at 0 -1.27 270)
			(size 1.524 1.524)
			(drill 0.9144)
			(layers "*.Cu" "*.Mask")
			(remove_unused_layers no)
			(net "L12_50OHM_6INCH")
			(clearance -0.0508)
			(thermal_gap 0.127)
			(padstack
				(mode front_inner_back)
				(layer "Inner"
					(shape circle)
					(size 1.1684 1.1684)
					(clearance 0.127)
				)
				(layer "B.Cu"
					(shape circle)
					(size 1.524 1.524)
					(clearance -0.0508)
				)
			)
		)
		(pad "GND1" thru_hole rect
			(at 0 1.27 270)
			(size 1.524 1.524)
			(drill 0.9144)
			(layers "*.Cu" "*.Mask")
			(remove_unused_layers no)
			(net "GND")
			(clearance -0.0508)
			(thermal_gap 0.127)
			(padstack
				(mode front_inner_back)
				(layer "Inner"
					(shape circle)
					(size 1.1684 1.1684)
					(clearance 0.127)
				)
				(layer "B.Cu"
					(shape rect)
					(size 1.524 1.524)
					(clearance -0.0508)
				)
			)
		)
	)
	(footprint ""
		(layer "F.Cu")
		(at 451.85838 -35.8775 90)
		(property "Reference" "R25W29"
			(at 0 0 90)
			(layer "F.SilkS")
			(hide yes)
			(effects
				(font
					(size 1.27 1.27)
				)
			)
		)
		(property "Value" "*"
			(at 0.064008 -4.108196 90)
			(unlocked yes)
			(layer "F.Fab")
			(hide yes)
			(effects
				(font
					(size 1.27 1.016)
					(thickness 0.1524)
				)
			)
		)
		(property "Device Type" "120R2F-GP_RCL_GP-120R2F-GP,64.A"
			(at 0.064008 -5.632196 90)
			(unlocked yes)
			(layer "F.Fab")
			(hide yes)
			(effects
				(font
					(size 1.27 1.016)
					(thickness 0.1524)
				)
			)
		)
		(duplicate_pad_numbers_are_jumpers no)
		(fp_line
			(start 0.508 -0.9398)
			(end -0.508 -0.9398)
			(stroke
				(width 0.1524)
				(type default)
			)
			(layer "F.SilkS")
		)
		(fp_line
			(start -0.508 -0.9398)
			(end -0.508 0.9398)
			(stroke
				(width 0.1524)
				(type default)
			)
			(layer "F.SilkS")
		)
		(fp_rect
			(start -0.508 0.9398)
			(end 0.508 -0.9398)
			(stroke
				(width 0)
				(type default)
			)
			(fill no)
			(layer "F.CrtYd")
		)
		(fp_rect
			(start -0.508 0.9398)
			(end 0.508 -0.9398)
			(stroke
				(width 0)
				(type default)
			)
			(fill no)
			(layer "F.Fab")
		)
		(pad "1" smd custom
			(at 0 -0.4445 90)
			(size 0.1397 0.1397)
			(layers "F.Cu" "F.Mask" "F.Paste")
			(net "BMC_M_RST_N")
			(options
				(clearance outline)
				(anchor circle)
			)
			(primitives
				(gr_poly
					(pts
						(arc
							(start -0.1778 -0.2794)
							(mid -0.249642 -0.249642)
							(end -0.2794 -0.1778)
						)
						(arc
							(start -0.2794 0.1778)
							(mid -0.249642 0.249642)
							(end -0.1778 0.2794)
						)
						(arc
							(start 0.1778 0.2794)
							(mid 0.249642 0.249642)
							(end 0.2794 0.1778)
						)
						(arc
							(start 0.2794 -0.1778)
							(mid 0.249642 -0.249642)
							(end 0.1778 -0.2794)
						)
					)
					(width 0)
					(fill yes)
				)
			)
		)
		(pad "2" smd custom
			(at 0 0.4445 90)
			(size 0.1397 0.1397)
			(layers "F.Cu" "F.Mask" "F.Paste")
			(net "P1V2_AUX_BMC")
			(options
				(clearance outline)
				(anchor circle)
			)
			(primitives
				(gr_poly
					(pts
						(arc
							(start -0.1778 -0.2794)
							(mid -0.249642 -0.249642)
							(end -0.2794 -0.1778)
						)
						(arc
							(start -0.2794 0.1778)
							(mid -0.249642 0.249642)
							(end -0.1778 0.2794)
						)
						(arc
							(start 0.1778 0.2794)
							(mid 0.249642 0.249642)
							(end 0.2794 0.1778)
						)
						(arc
							(start 0.2794 -0.1778)
							(mid 0.249642 -0.249642)
							(end 0.1778 -0.2794)
						)
					)
					(width 0)
					(fill yes)
				)
			)
		)
	)
	(footprint ""
		(layer "F.Cu")
		(at 415.1249 -51.5747 180)
		(property "Reference" "R1W6"
			(at 0 0 180)
			(layer "F.SilkS")
			(hide yes)
			(effects
				(font
					(size 1.27 1.27)
				)
			)
		)
		(property "Value" "*"
			(at 0.064008 -4.108196 180)
			(unlocked yes)
			(layer "F.Fab")
			(hide yes)
			(effects
				(font
					(size 1.27 1.016)
					(thickness 0.1524)
				)
			)
		)
		(property "Device Type" "1MR2F-L-GP_SMD-RG1-1MR2F-L-GP,A"
			(at 0.064008 -5.632196 180)
			(unlocked yes)
			(layer "F.Fab")
			(hide yes)
			(effects
				(font
					(size 1.27 1.016)
					(thickness 0.1524)
				)
			)
		)
		(duplicate_pad_numbers_are_jumpers no)
		(fp_line
			(start 0.508 -0.9398)
			(end -0.508 -0.9398)
			(stroke
				(width 0.1524)
				(type default)
			)
			(layer "F.SilkS")
		)
		(fp_line
			(start -0.508 -0.9398)
			(end -0.508 0.9398)
			(stroke
				(width 0.1524)
				(type default)
			)
			(layer "F.SilkS")
		)
		(fp_rect
			(start -0.508 0.9398)
			(end 0.508 -0.9398)
			(stroke
				(width 0)
				(type default)
			)
			(fill no)
			(layer "F.CrtYd")
		)
		(fp_rect
			(start -0.508 0.9398)
			(end 0.508 -0.9398)
			(stroke
				(width 0)
				(type default)
			)
			(fill no)
			(layer "F.Fab")
		)
		(pad "1" smd custom
			(at 0 -0.4445 180)
			(size 0.1397 0.1397)
			(layers "F.Cu" "F.Mask" "F.Paste")
			(net "P3V3_STBY")
			(options
				(clearance outline)
				(anchor circle)
			)
			(primitives
				(gr_poly
					(pts
						(arc
							(start -0.1778 -0.2794)
							(mid -0.249642 -0.249642)
							(end -0.2794 -0.1778)
						)
						(arc
							(start -0.2794 0.1778)
							(mid -0.249642 0.249642)
							(end -0.1778 0.2794)
						)
						(arc
							(start 0.1778 0.2794)
							(mid 0.249642 0.249642)
							(end 0.2794 0.1778)
						)
						(arc
							(start 0.2794 -0.1778)
							(mid 0.249642 -0.249642)
							(end 0.1778 -0.2794)
						)
					)
					(width 0)
					(fill yes)
				)
			)
		)
		(pad "2" smd custom
			(at 0 0.4445 180)
			(size 0.1397 0.1397)
			(layers "F.Cu" "F.Mask" "F.Paste")
			(net "FM_OCP_MEZZC_PRES_N")
			(options
				(clearance outline)
				(anchor circle)
			)
			(primitives
				(gr_poly
					(pts
						(arc
							(start -0.1778 -0.2794)
							(mid -0.249642 -0.249642)
							(end -0.2794 -0.1778)
						)
						(arc
							(start -0.2794 0.1778)
							(mid -0.249642 0.249642)
							(end -0.1778 0.2794)
						)
						(arc
							(start 0.1778 0.2794)
							(mid 0.249642 0.249642)
							(end 0.2794 0.1778)
						)
						(arc
							(start 0.2794 -0.1778)
							(mid 0.249642 -0.249642)
							(end 0.1778 -0.2794)
						)
					)
					(width 0)
					(fill yes)
				)
			)
		)
	)
	(footprint ""
		(layer "F.Cu")
		(at 460.463392 -41.512998)
		(property "Reference" "EU9F1"
			(at -0.256286 -1.396238 0)
			(unlocked yes)
			(layer "F.SilkS")
			(effects
				(font
					(size 0.7874 0.5842)
					(thickness 0.1524)
				)
				(justify left)
			)
		)
		(property "Value" ""
			(at 0 0 0)
			(layer "F.Fab")
			(effects
				(font
					(size 1.27 1.27)
				)
			)
		)
		(duplicate_pad_numbers_are_jumpers no)
		(fp_circle
			(center -0.835152 -0.417322)
			(end -0.708406 -0.417322)
			(stroke
				(width 0.254)
				(type default)
			)
			(fill no)
			(layer "F.SilkS")
		)
		(fp_poly
			(pts
				(xy -0.064516 -1.0922) (xy -0.064516 -0.3302) (xy 0.697484 -1.0922)
			)
			(stroke
				(width 0)
				(type default)
			)
			(fill yes)
			(layer "F.SilkS")
		)
		(fp_rect
			(start 0.597408 2.295398)
			(end 2.273808 -0.295402)
			(stroke
				(width 0)
				(type default)
			)
			(fill yes)
			(layer "F.Paste")
		)
		(fp_rect
			(start -0.064516 2.500122)
			(end 2.935478 -0.500126)
			(stroke
				(width 0)
				(type default)
			)
			(fill no)
			(layer "F.CrtYd")
		)
		(fp_line
			(start -0.064516 -0.500126)
			(end 2.935478 -0.500126)
			(stroke
				(width 0.1)
				(type default)
			)
			(layer "F.Fab")
		)
		(fp_line
			(start -0.064516 2.500122)
			(end -0.064516 -0.500126)
			(stroke
				(width 0.1)
				(type default)
			)
			(layer "F.Fab")
		)
		(fp_line
			(start 2.935478 -0.500126)
			(end 2.935478 2.500122)
			(stroke
				(width 0.1)
				(type default)
			)
			(layer "F.Fab")
		)
		(fp_line
			(start 2.935478 2.500122)
			(end -0.064516 2.500122)
			(stroke
				(width 0.1)
				(type default)
			)
			(layer "F.Fab")
		)
		(fp_circle
			(center -0.835152 -0.417322)
			(end -0.708406 -0.417322)
			(stroke
				(width 0.254)
				(type default)
			)
			(fill no)
			(layer "F.Fab")
		)
		(pad "1" smd rect
			(at 0 0)
			(size 0.6858 0.3048)
			(layers "F.Cu" "F.Mask" "F.Paste")
			(net "P1V15_AUX_BMC")
		)
		(pad "2" smd rect
			(at 0 0.500126)
			(size 0.6858 0.3048)
			(layers "F.Cu" "F.Mask" "F.Paste")
			(net "P1V15_AUX_BMC")
		)
		(pad "3" smd rect
			(at 0 0.999998)
			(size 0.6858 0.3048)
			(layers "F.Cu" "F.Mask" "F.Paste")
			(net "P1V15_AUX_BMC")
		)
		(pad "4" smd rect
			(at 0 1.500124)
			(size 0.6858 0.3048)
			(layers "F.Cu" "F.Mask" "F.Paste")
			(net "VR_P1V15_BMC_STBY_FB")
		)
		(pad "5" smd rect
			(at 0 1.999996)
			(size 0.6858 0.3048)
			(layers "F.Cu" "F.Mask" "F.Paste")
			(net "PWRGD_P1V15_BMC_STBY_R")
		)
		(pad "6" smd rect
			(at 2.871216 1.999996)
			(size 0.6858 0.3048)
			(layers "F.Cu" "F.Mask" "F.Paste")
			(net "PWRGD_P1V2_BMC_STBY")
		)
		(pad "7" smd rect
			(at 2.871216 1.500124)
			(size 0.6858 0.3048)
			(layers "F.Cu" "F.Mask" "F.Paste")
			(net "P3V3_STBY")
		)
		(pad "8" smd rect
			(at 2.871216 0.999998)
			(size 0.6858 0.3048)
			(layers "F.Cu" "F.Mask" "F.Paste")
			(net "P3V3_STBY")
		)
		(pad "9" smd rect
			(at 2.871216 0.500126)
			(size 0.6858 0.3048)
			(layers "F.Cu" "F.Mask" "F.Paste")
			(net "P3V3_STBY")
		)
		(pad "10" smd rect
			(at 2.871216 0)
			(size 0.6858 0.3048)
			(layers "F.Cu" "F.Mask" "F.Paste")
			(net "P3V3_STBY")
		)
		(pad "11" smd rect
			(at 1.435608 0.999998)
			(size 1.6764 2.5908)
			(layers "F.Cu" "F.Mask" "F.Paste")
			(net "GND")
		)
	)
	(footprint ""
		(layer "F.Cu")
		(at 378.254768 -33.7185 90)
		(property "Reference" "C8F6"
			(at 0 0 90)
			(layer "F.SilkS")
			(hide yes)
			(effects
				(font
					(size 1.27 1.27)
				)
			)
		)
		(property "Value" ""
			(at 0 0 90)
			(layer "F.Fab")
			(effects
				(font
					(size 1.27 1.27)
				)
			)
		)
		(duplicate_pad_numbers_are_jumpers no)
		(fp_poly
			(pts
				(xy 0.3048 -0.1016) (xy 0.3048 0.9906) (xy -0.3048 0.9906) (xy -0.3048 -0.1016)
			)
			(stroke
				(width 0)
				(type default)
			)
			(fill no)
			(layer "F.CrtYd")
		)
		(fp_line
			(start 0.3048 -0.1016)
			(end -0.3048 -0.1016)
			(stroke
				(width 0.1)
				(type default)
			)
			(layer "F.Fab")
		)
		(fp_line
			(start -0.3048 -0.1016)
			(end -0.3048 0.9906)
			(stroke
				(width 0.1)
				(type default)
			)
			(layer "F.Fab")
		)
		(fp_line
			(start 0.3048 0.9906)
			(end 0.3048 -0.1016)
			(stroke
				(width 0.1)
				(type default)
			)
			(layer "F.Fab")
		)
		(fp_line
			(start -0.3048 0.9906)
			(end 0.3048 0.9906)
			(stroke
				(width 0.1)
				(type default)
			)
			(layer "F.Fab")
		)
		(pad "1" smd rect
			(at 0 0 90)
			(size 0.508 0.508)
			(layers "F.Cu" "F.Mask" "F.Paste")
			(net "SATA6G_S0_TX_DP")
		)
		(pad "2" smd rect
			(at 0 0.889 90)
			(size 0.508 0.508)
			(layers "F.Cu" "F.Mask" "F.Paste")
			(net "P3E_PCH_M2_SATA6G_TX_R_DP")
		)
		(zone
			(layer "F.Cu")
			(hatch none 0.5)
			(connect_pads
				(clearance 0)
			)
			(min_thickness 0.25)
			(keepout
				(tracks allowed)
				(vias not_allowed)
				(pads allowed)
				(copperpour not_allowed)
				(footprints allowed)
			)
			(placement
				(enabled no)
				(sheetname "")
			)
			(fill
				(thermal_gap 0.5)
				(thermal_bridge_width 0.5)
				(island_removal_mode 0)
			)
			(polygon
				(pts
					(xy 378.508768 -33.4645) (xy 378.508768 -33.9725) (xy 378.889768 -33.9725) (xy 378.889768 -33.4645)
				)
			)
		)
		(zone
			(layer "F.Cu")
			(hatch none 0.5)
			(connect_pads
				(clearance 0)
			)
			(min_thickness 0.25)
			(keepout
				(tracks not_allowed)
				(vias allowed)
				(pads allowed)
				(copperpour not_allowed)
				(footprints allowed)
			)
			(placement
				(enabled no)
				(sheetname "")
			)
			(fill
				(thermal_gap 0.5)
				(thermal_bridge_width 0.5)
				(island_removal_mode 0)
			)
			(polygon
				(pts
					(xy 378.889768 -33.4645) (xy 378.889768 -33.9725) (xy 378.508768 -33.9725) (xy 378.508768 -33.4645)
				)
			)
		)
	)
	(footprint ""
		(layer "F.Cu")
		(at 339.222588 -117.941598 -90)
		(property "Reference" "C845"
			(at -0.8382 -0.67818 270)
			(unlocked yes)
			(layer "F.SilkS")
			(effects
				(font
					(size 0.4064 0.254)
					(thickness 0.1524)
				)
				(justify left)
			)
		)
		(property "Value" ""
			(at 0 0 270)
			(layer "F.Fab")
			(effects
				(font
					(size 1.27 1.27)
				)
			)
		)
		(duplicate_pad_numbers_are_jumpers no)
		(fp_poly
			(pts
				(xy 0.3048 -0.1016) (xy 0.3048 0.9906) (xy -0.3048 0.9906) (xy -0.3048 -0.1016)
			)
			(stroke
				(width 0)
				(type default)
			)
			(fill no)
			(layer "F.CrtYd")
		)
		(fp_line
			(start -0.3048 0.9906)
			(end 0.3048 0.9906)
			(stroke
				(width 0.1)
				(type default)
			)
			(layer "F.Fab")
		)
		(fp_line
			(start 0.3048 0.9906)
			(end 0.3048 -0.1016)
			(stroke
				(width 0.1)
				(type default)
			)
			(layer "F.Fab")
		)
		(fp_line
			(start -0.3048 -0.1016)
			(end -0.3048 0.9906)
			(stroke
				(width 0.1)
				(type default)
			)
			(layer "F.Fab")
		)
		(fp_line
			(start 0.3048 -0.1016)
			(end -0.3048 -0.1016)
			(stroke
				(width 0.1)
				(type default)
			)
			(layer "F.Fab")
		)
		(pad "1" smd rect
			(at 0 0 270)
			(size 0.508 0.508)
			(layers "F.Cu" "F.Mask" "F.Paste")
			(net "P3E_CPU0_PE1_PCH_TXP<9>")
		)
		(pad "2" smd rect
			(at 0 0.889 270)
			(size 0.508 0.508)
			(layers "F.Cu" "F.Mask" "F.Paste")
			(net "P3E_CPU0_PE1_PCH_CON_TXP<9>")
		)
		(zone
			(layer "F.Cu")
			(hatch none 0.5)
			(connect_pads
				(clearance 0)
			)
			(min_thickness 0.25)
			(keepout
				(tracks not_allowed)
				(vias allowed)
				(pads allowed)
				(copperpour not_allowed)
				(footprints allowed)
			)
			(placement
				(enabled no)
				(sheetname "")
			)
			(fill
				(thermal_gap 0.5)
				(thermal_bridge_width 0.5)
				(island_removal_mode 0)
			)
			(polygon
				(pts
					(xy 338.587588 -118.195598) (xy 338.587588 -117.687598) (xy 338.968588 -117.687598) (xy 338.968588 -118.195598)
				)
			)
		)
		(zone
			(layer "F.Cu")
			(hatch none 0.5)
			(connect_pads
				(clearance 0)
			)
			(min_thickness 0.25)
			(keepout
				(tracks allowed)
				(vias not_allowed)
				(pads allowed)
				(copperpour not_allowed)
				(footprints allowed)
			)
			(placement
				(enabled no)
				(sheetname "")
			)
			(fill
				(thermal_gap 0.5)
				(thermal_bridge_width 0.5)
				(island_removal_mode 0)
			)
			(polygon
				(pts
					(xy 338.968588 -118.195598) (xy 338.968588 -117.687598) (xy 338.587588 -117.687598) (xy 338.587588 -118.195598)
				)
			)
		)
	)
)
